(kicad_pcb
	(version 20260206)
	(generator "pcbnew")
	(generator_version "10.0")
	(general
		(thickness 1.6)
		(legacy_teardrops no)
	)
	(paper "A4")
	(title_block
		(title "04192023_DAF0TMB3IC0_F0TG_MB_C_brd_V02_OCP.brd")
		(comment 1 "Grand Teton / footprints 7419-7425 of 8354")
	)
	(layers
		(0 "F.Cu" signal "TOP")
		(4 "In1.Cu" signal "GND")
		(6 "In2.Cu" signal "IN1")
		(8 "In3.Cu" signal "GND1")
		(10 "In4.Cu" signal "IN2")
		(12 "In5.Cu" signal "GND2")
		(14 "In6.Cu" signal "IN3")
		(16 "In7.Cu" signal "GND3")
		(18 "In8.Cu" signal "VCC")
		(20 "In9.Cu" signal "VCC1")
		(22 "In10.Cu" signal "GND4")
		(24 "In11.Cu" signal "IN4")
		(26 "In12.Cu" signal "GND5")
		(28 "In13.Cu" signal "IN5")
		(30 "In14.Cu" signal "GND6")
		(32 "In15.Cu" signal "IN6")
		(34 "In16.Cu" signal "GND7")
		(2 "B.Cu" signal "BOTTOM")
		(9 "F.Adhes" user "F.Adhesive")
		(11 "B.Adhes" user "B.Adhesive")
		(13 "F.Paste" user "Package Geometry/Pastemask Top")
		(15 "B.Paste" user "Package Geometry/Pastemask Bottom")
		(5 "F.SilkS" user "Ref Des/Silkscreen Top")
		(7 "B.SilkS" user "Ref Des/Silkscreen Bottom")
		(1 "F.Mask" user "Board Geometry/Soldermask Top")
		(3 "B.Mask" user "Board Geometry/Soldermask Bottom")
		(17 "Dwgs.User" user "User.Drawings")
		(19 "Cmts.User" user "User.Comments")
		(21 "Eco1.User" user "User.Eco1")
		(23 "Eco2.User" user "User.Eco2")
		(25 "Edge.Cuts" user "Board Geometry/Outline")
		(27 "Margin" user)
		(31 "F.CrtYd" user "Package Geometry/Place Bound Top")
		(29 "B.CrtYd" user "Package Geometry/Place Bound Bottom")
		(35 "F.Fab" user "Ref Des/Assembly Top")
		(33 "B.Fab" user "Ref Des/Assembly Bottom")
	)
	(footprint ""
		(layer "B.Cu")
		(at 71.530718 -338.939632 -90)
		(property "Reference" "PC410_3"
			(at 0 0 90)
			(layer "B.SilkS")
			(hide yes)
			(effects
				(font
					(size 1.27 1.27)
				)
				(justify mirror)
			)
		)
		(property "Value" ""
			(at 0 0 90)
			(layer "B.Fab")
			(effects
				(font
					(size 1.27 1.27)
				)
				(justify mirror)
			)
		)
		(duplicate_pad_numbers_are_jumpers no)
		(fp_line
			(start -1.524 0.762)
			(end 1.524 0.762)
			(stroke
				(width 0.1524)
				(type default)
			)
			(layer "B.SilkS")
		)
		(fp_line
			(start 1.524 0.762)
			(end 1.524 -0.762)
			(stroke
				(width 0.1524)
				(type default)
			)
			(layer "B.SilkS")
		)
		(fp_line
			(start -1.524 -0.762)
			(end -1.524 0.762)
			(stroke
				(width 0.1524)
				(type default)
			)
			(layer "B.SilkS")
		)
		(fp_line
			(start 1.524 -0.762)
			(end -1.524 -0.762)
			(stroke
				(width 0.1524)
				(type default)
			)
			(layer "B.SilkS")
		)
		(fp_line
			(start -1.1049 0.724916)
			(end -1.1049 -0.724916)
			(stroke
				(width 0.1)
				(type default)
			)
			(layer "B.Fab")
		)
		(fp_line
			(start 1.1049 0.724916)
			(end -1.1049 0.724916)
			(stroke
				(width 0.1)
				(type default)
			)
			(layer "B.Fab")
		)
		(fp_line
			(start -1.1049 -0.724916)
			(end 1.1049 -0.724916)
			(stroke
				(width 0.1)
				(type default)
			)
			(layer "B.Fab")
		)
		(fp_line
			(start 1.1049 -0.724916)
			(end 1.1049 0.724916)
			(stroke
				(width 0.1)
				(type default)
			)
			(layer "B.Fab")
		)
		(pad "1" smd rect
			(at 0.889 0 270)
			(size 1.016 1.27)
			(layers "B.Cu" "B.Mask" "B.Paste")
			(net "SW_P12V_AUX_PVDDCR_CPU1_P1_FLT")
		)
		(pad "2" smd rect
			(at -0.889 0 270)
			(size 1.016 1.27)
			(layers "B.Cu" "B.Mask" "B.Paste")
			(net "GND")
		)
	)
	(footprint ""
		(layer "B.Cu")
		(at 111.17834 -62.01791 -90)
		(property "Reference" "R6224"
			(at 0 0 90)
			(layer "B.SilkS")
			(hide yes)
			(effects
				(font
					(size 1.27 1.27)
				)
				(justify mirror)
			)
		)
		(property "Value" ""
			(at 0 0 90)
			(layer "B.Fab")
			(effects
				(font
					(size 1.27 1.27)
				)
				(justify mirror)
			)
		)
		(duplicate_pad_numbers_are_jumpers no)
		(fp_line
			(start -0.7874 0.4064)
			(end 0.7874 0.4064)
			(stroke
				(width 0.1524)
				(type default)
			)
			(layer "B.SilkS")
		)
		(fp_line
			(start 0.7874 0.4064)
			(end 0.7874 -0.4064)
			(stroke
				(width 0.1524)
				(type default)
			)
			(layer "B.SilkS")
		)
		(fp_line
			(start -0.7874 -0.4064)
			(end -0.7874 0.4064)
			(stroke
				(width 0.1524)
				(type default)
			)
			(layer "B.SilkS")
		)
		(fp_line
			(start 0.7874 -0.4064)
			(end -0.7874 -0.4064)
			(stroke
				(width 0.1524)
				(type default)
			)
			(layer "B.SilkS")
		)
		(fp_line
			(start -0.67945 0.3048)
			(end -0.120396 0.3048)
			(stroke
				(width 0.1)
				(type default)
			)
			(layer "B.Fab")
		)
		(fp_line
			(start -0.120396 0.3048)
			(end -0.120396 0.2794)
			(stroke
				(width 0.1)
				(type default)
			)
			(layer "B.Fab")
		)
		(fp_line
			(start 0.12065 0.3048)
			(end 0.67945 0.3048)
			(stroke
				(width 0.1)
				(type default)
			)
			(layer "B.Fab")
		)
		(fp_line
			(start 0.67945 0.3048)
			(end 0.67945 -0.305054)
			(stroke
				(width 0.1)
				(type default)
			)
			(layer "B.Fab")
		)
		(fp_line
			(start -0.120396 0.2794)
			(end 0.12065 0.2794)
			(stroke
				(width 0.1)
				(type default)
			)
			(layer "B.Fab")
		)
		(fp_line
			(start 0.12065 0.2794)
			(end 0.12065 0.3048)
			(stroke
				(width 0.1)
				(type default)
			)
			(layer "B.Fab")
		)
		(fp_line
			(start -0.12065 -0.2794)
			(end -0.12065 -0.3048)
			(stroke
				(width 0.1)
				(type default)
			)
			(layer "B.Fab")
		)
		(fp_line
			(start 0.12065 -0.2794)
			(end -0.12065 -0.2794)
			(stroke
				(width 0.1)
				(type default)
			)
			(layer "B.Fab")
		)
		(fp_line
			(start -0.67945 -0.3048)
			(end -0.67945 0.3048)
			(stroke
				(width 0.1)
				(type default)
			)
			(layer "B.Fab")
		)
		(fp_line
			(start -0.12065 -0.3048)
			(end -0.67945 -0.3048)
			(stroke
				(width 0.1)
				(type default)
			)
			(layer "B.Fab")
		)
		(fp_line
			(start 0.12065 -0.305054)
			(end 0.12065 -0.2794)
			(stroke
				(width 0.1)
				(type default)
			)
			(layer "B.Fab")
		)
		(fp_line
			(start 0.67945 -0.305054)
			(end 0.12065 -0.305054)
			(stroke
				(width 0.1)
				(type default)
			)
			(layer "B.Fab")
		)
		(pad "1" smd circle
			(at 0.40005 0 90)
			(size 0 0)
			(layers "B.Cu" "B.Mask" "B.Paste")
			(net "SMB_USB_CPU0_HUB1_SCL")
		)
		(pad "2" smd circle
			(at -0.40005 0 90)
			(size 0 0)
			(layers "B.Cu" "B.Mask" "B.Paste")
			(net "SMB_USB_CPU0_HUB1_SCL_R2")
		)
	)
	(footprint ""
		(layer "B.Cu")
		(at 201.041 -140.462 90)
		(property "Reference" "U8004"
			(at -2.036826 -2.62509 270)
			(unlocked yes)
			(layer "B.SilkS")
			(effects
				(font
					(size 0.7874 0.5842)
					(thickness 0.1524)
				)
				(justify left mirror)
			)
		)
		(property "Value" ""
			(at 0 0 90)
			(layer "B.Fab")
			(effects
				(font
					(size 1.27 1.27)
				)
				(justify mirror)
			)
		)
		(duplicate_pad_numbers_are_jumpers no)
		(fp_line
			(start 1.38176 -1.100074)
			(end 1.38176 1.100074)
			(stroke
				(width 0.1524)
				(type default)
			)
			(layer "B.SilkS")
		)
		(fp_line
			(start 0.592074 -1.100074)
			(end 1.38176 -1.100074)
			(stroke
				(width 0.1524)
				(type default)
			)
			(layer "B.SilkS")
		)
		(fp_line
			(start -0.592074 -1.100074)
			(end 0 -0.508)
			(stroke
				(width 0.1524)
				(type default)
			)
			(layer "B.SilkS")
		)
		(fp_line
			(start -1.38176 -1.100074)
			(end -0.592074 -1.100074)
			(stroke
				(width 0.1524)
				(type default)
			)
			(layer "B.SilkS")
		)
		(fp_line
			(start 0 -0.508)
			(end 0.592074 -1.100074)
			(stroke
				(width 0.1524)
				(type default)
			)
			(layer "B.SilkS")
		)
		(fp_line
			(start 1.38176 1.100074)
			(end -1.38176 1.100074)
			(stroke
				(width 0.1524)
				(type default)
			)
			(layer "B.SilkS")
		)
		(fp_line
			(start -1.38176 1.100074)
			(end -1.38176 -1.100074)
			(stroke
				(width 0.1524)
				(type default)
			)
			(layer "B.SilkS")
		)
		(fp_poly
			(pts
				(xy 1.9431 -0.870204) (xy 1.50241 -0.649986) (xy 1.9431 -0.429768)
			)
			(stroke
				(width 0)
				(type default)
			)
			(fill yes)
			(layer "B.SilkS")
		)
		(fp_line
			(start 0.674878 -1.100074)
			(end 0.674878 1.100074)
			(stroke
				(width 0.1)
				(type default)
			)
			(layer "B.Fab")
		)
		(fp_line
			(start -0.674878 -1.100074)
			(end 0.674878 -1.100074)
			(stroke
				(width 0.1)
				(type default)
			)
			(layer "B.Fab")
		)
		(fp_line
			(start 0.674878 1.100074)
			(end -0.674878 1.100074)
			(stroke
				(width 0.1)
				(type default)
			)
			(layer "B.Fab")
		)
		(fp_line
			(start -0.674878 1.100074)
			(end -0.674878 -1.100074)
			(stroke
				(width 0.1)
				(type default)
			)
			(layer "B.Fab")
		)
		(fp_poly
			(pts
				(xy 1.9431 -0.870204) (xy 1.50241 -0.649986) (xy 1.9431 -0.429768)
			)
			(stroke
				(width 0)
				(type default)
			)
			(fill yes)
			(layer "B.Fab")
		)
		(pad "1" smd rect
			(at 0.94996 -0.649986)
			(size 0.4318 0.6096)
			(layers "B.Cu" "B.Mask" "B.Paste")
			(net "FM_AC_PWR_BTN_PLD_N")
		)
		(pad "2" smd rect
			(at 0.94996 0)
			(size 0.4318 0.6096)
			(layers "B.Cu" "B.Mask" "B.Paste")
			(net "GND")
		)
		(pad "3" smd rect
			(at 0.94996 0.649986)
			(size 0.4318 0.6096)
			(layers "B.Cu" "B.Mask" "B.Paste")
			(net "GND")
		)
		(pad "4" smd rect
			(at -0.94996 0.649986)
			(size 0.4318 0.6096)
			(layers "B.Cu" "B.Mask" "B.Paste")
			(net "NC_U8004_2Y")
		)
		(pad "5" smd rect
			(at -0.94996 0)
			(size 0.4318 0.6096)
			(layers "B.Cu" "B.Mask" "B.Paste")
			(net "P3V3_AUX")
		)
		(pad "6" smd rect
			(at -0.94996 -0.649986)
			(size 0.4318 0.6096)
			(layers "B.Cu" "B.Mask" "B.Paste")
			(net "FM_AC_PWR_BTN_PLD_ISO_R_N")
		)
	)
	(footprint ""
		(layer "B.Cu")
		(at 428.98695 -41.087548)
		(property "Reference" "R6044"
			(at 0 0 0)
			(layer "B.SilkS")
			(hide yes)
			(effects
				(font
					(size 1.27 1.27)
				)
				(justify mirror)
			)
		)
		(property "Value" ""
			(at 0 0 0)
			(layer "B.Fab")
			(effects
				(font
					(size 1.27 1.27)
				)
				(justify mirror)
			)
		)
		(duplicate_pad_numbers_are_jumpers no)
		(fp_line
			(start -0.7874 -0.4064)
			(end -0.7874 0.4064)
			(stroke
				(width 0.1524)
				(type default)
			)
			(layer "B.SilkS")
		)
		(fp_line
			(start -0.7874 0.4064)
			(end 0.7874 0.4064)
			(stroke
				(width 0.1524)
				(type default)
			)
			(layer "B.SilkS")
		)
		(fp_line
			(start 0.7874 -0.4064)
			(end -0.7874 -0.4064)
			(stroke
				(width 0.1524)
				(type default)
			)
			(layer "B.SilkS")
		)
		(fp_line
			(start 0.7874 0.4064)
			(end 0.7874 -0.4064)
			(stroke
				(width 0.1524)
				(type default)
			)
			(layer "B.SilkS")
		)
		(fp_line
			(start -0.67945 -0.3048)
			(end -0.67945 0.3048)
			(stroke
				(width 0.1)
				(type default)
			)
			(layer "B.Fab")
		)
		(fp_line
			(start -0.67945 0.3048)
			(end -0.120396 0.3048)
			(stroke
				(width 0.1)
				(type default)
			)
			(layer "B.Fab")
		)
		(fp_line
			(start -0.12065 -0.3048)
			(end -0.67945 -0.3048)
			(stroke
				(width 0.1)
				(type default)
			)
			(layer "B.Fab")
		)
		(fp_line
			(start -0.12065 -0.2794)
			(end -0.12065 -0.3048)
			(stroke
				(width 0.1)
				(type default)
			)
			(layer "B.Fab")
		)
		(fp_line
			(start -0.120396 0.2794)
			(end 0.12065 0.2794)
			(stroke
				(width 0.1)
				(type default)
			)
			(layer "B.Fab")
		)
		(fp_line
			(start -0.120396 0.3048)
			(end -0.120396 0.2794)
			(stroke
				(width 0.1)
				(type default)
			)
			(layer "B.Fab")
		)
		(fp_line
			(start 0.12065 -0.305054)
			(end 0.12065 -0.2794)
			(stroke
				(width 0.1)
				(type default)
			)
			(layer "B.Fab")
		)
		(fp_line
			(start 0.12065 -0.2794)
			(end -0.12065 -0.2794)
			(stroke
				(width 0.1)
				(type default)
			)
			(layer "B.Fab")
		)
		(fp_line
			(start 0.12065 0.2794)
			(end 0.12065 0.3048)
			(stroke
				(width 0.1)
				(type default)
			)
			(layer "B.Fab")
		)
		(fp_line
			(start 0.12065 0.3048)
			(end 0.67945 0.3048)
			(stroke
				(width 0.1)
				(type default)
			)
			(layer "B.Fab")
		)
		(fp_line
			(start 0.67945 -0.305054)
			(end 0.12065 -0.305054)
			(stroke
				(width 0.1)
				(type default)
			)
			(layer "B.Fab")
		)
		(fp_line
			(start 0.67945 0.3048)
			(end 0.67945 -0.305054)
			(stroke
				(width 0.1)
				(type default)
			)
			(layer "B.Fab")
		)
		(pad "1" smd circle
			(at 0.40005 0 180)
			(size 0 0)
			(layers "B.Cu" "B.Mask" "B.Paste")
			(net "FM_FORCE_ALL_PWRON")
		)
		(pad "2" smd circle
			(at -0.40005 0 180)
			(size 0 0)
			(layers "B.Cu" "B.Mask" "B.Paste")
			(net "GND")
		)
	)
	(footprint ""
		(layer "B.Cu")
		(at 291.849048 -337.984846 -90)
		(property "Reference" "PC168_2"
			(at 0 0 90)
			(layer "B.SilkS")
			(hide yes)
			(effects
				(font
					(size 1.27 1.27)
				)
				(justify mirror)
			)
		)
		(property "Value" ""
			(at 0 0 90)
			(layer "B.Fab")
			(effects
				(font
					(size 1.27 1.27)
				)
				(justify mirror)
			)
		)
		(duplicate_pad_numbers_are_jumpers no)
		(fp_line
			(start -1.524 0.762)
			(end 1.524 0.762)
			(stroke
				(width 0.1524)
				(type default)
			)
			(layer "B.SilkS")
		)
		(fp_line
			(start 1.524 0.762)
			(end 1.524 -0.762)
			(stroke
				(width 0.1524)
				(type default)
			)
			(layer "B.SilkS")
		)
		(fp_line
			(start -1.524 -0.762)
			(end -1.524 0.762)
			(stroke
				(width 0.1524)
				(type default)
			)
			(layer "B.SilkS")
		)
		(fp_line
			(start 1.524 -0.762)
			(end -1.524 -0.762)
			(stroke
				(width 0.1524)
				(type default)
			)
			(layer "B.SilkS")
		)
		(fp_line
			(start -1.1049 0.724916)
			(end -1.1049 -0.724916)
			(stroke
				(width 0.1)
				(type default)
			)
			(layer "B.Fab")
		)
		(fp_line
			(start 1.1049 0.724916)
			(end -1.1049 0.724916)
			(stroke
				(width 0.1)
				(type default)
			)
			(layer "B.Fab")
		)
		(fp_line
			(start -1.1049 -0.724916)
			(end 1.1049 -0.724916)
			(stroke
				(width 0.1)
				(type default)
			)
			(layer "B.Fab")
		)
		(fp_line
			(start 1.1049 -0.724916)
			(end 1.1049 0.724916)
			(stroke
				(width 0.1)
				(type default)
			)
			(layer "B.Fab")
		)
		(pad "1" smd rect
			(at 0.889 0 270)
			(size 1.016 1.27)
			(layers "B.Cu" "B.Mask" "B.Paste")
			(net "PVDDIO_P0")
		)
		(pad "2" smd rect
			(at -0.889 0 270)
			(size 1.016 1.27)
			(layers "B.Cu" "B.Mask" "B.Paste")
			(net "GND")
		)
	)
	(footprint ""
		(layer "B.Cu")
		(at 100.144834 -271.903952 90)
		(property "Reference" "C2382"
			(at 0 0 90)
			(layer "B.SilkS")
			(hide yes)
			(effects
				(font
					(size 1.27 1.27)
				)
				(justify mirror)
			)
		)
		(property "Value" ""
			(at 0 0 90)
			(layer "B.Fab")
			(effects
				(font
					(size 1.27 1.27)
				)
				(justify mirror)
			)
		)
		(duplicate_pad_numbers_are_jumpers no)
		(fp_line
			(start 0.7874 -0.4064)
			(end -0.7874 -0.4064)
			(stroke
				(width 0.1524)
				(type default)
			)
			(layer "B.SilkS")
		)
		(fp_line
			(start -0.7874 -0.4064)
			(end -0.7874 0.4064)
			(stroke
				(width 0.1524)
				(type default)
			)
			(layer "B.SilkS")
		)
		(fp_line
			(start 0.7874 0.4064)
			(end 0.7874 -0.4064)
			(stroke
				(width 0.1524)
				(type default)
			)
			(layer "B.SilkS")
		)
		(fp_line
			(start -0.7874 0.4064)
			(end 0.7874 0.4064)
			(stroke
				(width 0.1524)
				(type default)
			)
			(layer "B.SilkS")
		)
		(fp_line
			(start 0.67945 -0.305054)
			(end 0.12065 -0.305054)
			(stroke
				(width 0.1)
				(type default)
			)
			(layer "B.Fab")
		)
		(fp_line
			(start 0.12065 -0.305054)
			(end 0.12065 -0.2794)
			(stroke
				(width 0.1)
				(type default)
			)
			(layer "B.Fab")
		)
		(fp_line
			(start -0.12065 -0.3048)
			(end -0.67945 -0.3048)
			(stroke
				(width 0.1)
				(type default)
			)
			(layer "B.Fab")
		)
		(fp_line
			(start -0.67945 -0.3048)
			(end -0.67945 0.3048)
			(stroke
				(width 0.1)
				(type default)
			)
			(layer "B.Fab")
		)
		(fp_line
			(start 0.12065 -0.2794)
			(end -0.12065 -0.2794)
			(stroke
				(width 0.1)
				(type default)
			)
			(layer "B.Fab")
		)
		(fp_line
			(start -0.12065 -0.2794)
			(end -0.12065 -0.3048)
			(stroke
				(width 0.1)
				(type default)
			)
			(layer "B.Fab")
		)
		(fp_line
			(start 0.12065 0.2794)
			(end 0.12065 0.3048)
			(stroke
				(width 0.1)
				(type default)
			)
			(layer "B.Fab")
		)
		(fp_line
			(start -0.120396 0.2794)
			(end 0.12065 0.2794)
			(stroke
				(width 0.1)
				(type default)
			)
			(layer "B.Fab")
		)
		(fp_line
			(start 0.67945 0.3048)
			(end 0.67945 -0.305054)
			(stroke
				(width 0.1)
				(type default)
			)
			(layer "B.Fab")
		)
		(fp_line
			(start 0.12065 0.3048)
			(end 0.67945 0.3048)
			(stroke
				(width 0.1)
				(type default)
			)
			(layer "B.Fab")
		)
		(fp_line
			(start -0.120396 0.3048)
			(end -0.120396 0.2794)
			(stroke
				(width 0.1)
				(type default)
			)
			(layer "B.Fab")
		)
		(fp_line
			(start -0.67945 0.3048)
			(end -0.120396 0.3048)
			(stroke
				(width 0.1)
				(type default)
			)
			(layer "B.Fab")
		)
		(pad "1" smd circle
			(at 0.40005 0 270)
			(size 0 0)
			(layers "B.Cu" "B.Mask" "B.Paste")
			(net "PVDDCR_CPU1_P1")
		)
		(pad "2" smd circle
			(at -0.40005 0 270)
			(size 0 0)
			(layers "B.Cu" "B.Mask" "B.Paste")
			(net "GND")
		)
	)
	(footprint ""
		(layer "B.Cu")
		(at 457.702666 -389.23087 -90)
		(property "Reference" "PC6806"
			(at 0 0 90)
			(layer "B.SilkS")
			(hide yes)
			(effects
				(font
					(size 1.27 1.27)
				)
				(justify mirror)
			)
		)
		(property "Value" ""
			(at 0 0 90)
			(layer "B.Fab")
			(effects
				(font
					(size 1.27 1.27)
				)
				(justify mirror)
			)
		)
		(duplicate_pad_numbers_are_jumpers no)
		(fp_line
			(start -0.7874 0.4064)
			(end 0.7874 0.4064)
			(stroke
				(width 0.1524)
				(type default)
			)
			(layer "B.SilkS")
		)
		(fp_line
			(start 0.7874 0.4064)
			(end 0.7874 -0.4064)
			(stroke
				(width 0.1524)
				(type default)
			)
			(layer "B.SilkS")
		)
		(fp_line
			(start -0.7874 -0.4064)
			(end -0.7874 0.4064)
			(stroke
				(width 0.1524)
				(type default)
			)
			(layer "B.SilkS")
		)
		(fp_line
			(start 0.7874 -0.4064)
			(end -0.7874 -0.4064)
			(stroke
				(width 0.1524)
				(type default)
			)
			(layer "B.SilkS")
		)
		(fp_line
			(start -0.67945 0.3048)
			(end -0.120396 0.3048)
			(stroke
				(width 0.1)
				(type default)
			)
			(layer "B.Fab")
		)
		(fp_line
			(start -0.120396 0.3048)
			(end -0.120396 0.2794)
			(stroke
				(width 0.1)
				(type default)
			)
			(layer "B.Fab")
		)
		(fp_line
			(start 0.12065 0.3048)
			(end 0.67945 0.3048)
			(stroke
				(width 0.1)
				(type default)
			)
			(layer "B.Fab")
		)
		(fp_line
			(start 0.67945 0.3048)
			(end 0.67945 -0.305054)
			(stroke
				(width 0.1)
				(type default)
			)
			(layer "B.Fab")
		)
		(fp_line
			(start -0.120396 0.2794)
			(end 0.12065 0.2794)
			(stroke
				(width 0.1)
				(type default)
			)
			(layer "B.Fab")
		)
		(fp_line
			(start 0.12065 0.2794)
			(end 0.12065 0.3048)
			(stroke
				(width 0.1)
				(type default)
			)
			(layer "B.Fab")
		)
		(fp_line
			(start -0.12065 -0.2794)
			(end -0.12065 -0.3048)
			(stroke
				(width 0.1)
				(type default)
			)
			(layer "B.Fab")
		)
		(fp_line
			(start 0.12065 -0.2794)
			(end -0.12065 -0.2794)
			(stroke
				(width 0.1)
				(type default)
			)
			(layer "B.Fab")
		)
		(fp_line
			(start -0.67945 -0.3048)
			(end -0.67945 0.3048)
			(stroke
				(width 0.1)
				(type default)
			)
			(layer "B.Fab")
		)
		(fp_line
			(start -0.12065 -0.3048)
			(end -0.67945 -0.3048)
			(stroke
				(width 0.1)
				(type default)
			)
			(layer "B.Fab")
		)
		(fp_line
			(start 0.12065 -0.305054)
			(end 0.12065 -0.2794)
			(stroke
				(width 0.1)
				(type default)
			)
			(layer "B.Fab")
		)
		(fp_line
			(start 0.67945 -0.305054)
			(end 0.12065 -0.305054)
			(stroke
				(width 0.1)
				(type default)
			)
			(layer "B.Fab")
		)
		(pad "1" smd circle
			(at 0.40005 0 90)
			(size 0 0)
			(layers "B.Cu" "B.Mask" "B.Paste")
			(net "P0V9_CPU0_RT_2D")
		)
		(pad "2" smd circle
			(at -0.40005 0 90)
			(size 0 0)
			(layers "B.Cu" "B.Mask" "B.Paste")
			(net "GND")
		)
	)
)
